(kicad_pcb
	(version 20221018)
	(generator pcbnew)
	(general
    (thickness 0.908)
  )
	(paper "A4")
	(title_block
    (title "HDMI-MIPI Bridge")
    (date "2024-04-24")
    (rev "1.3.2")
		(comment 9 "footprints 47-51 of 121")
	)
	(layers
    (0 "F.Cu" signal)
    (1 "In1.Cu" signal)
    (2 "In2.Cu" signal)
    (31 "B.Cu" signal)
    (32 "B.Adhes" user "B.Adhesive")
    (33 "F.Adhes" user "F.Adhesive")
    (34 "B.Paste" user)
    (35 "F.Paste" user)
    (36 "B.SilkS" user "B.Silkscreen")
    (37 "F.SilkS" user "F.Silkscreen")
    (38 "B.Mask" user)
    (39 "F.Mask" user)
    (40 "Dwgs.User" user "User.Drawings")
    (41 "Cmts.User" user "User.Comments")
    (42 "Eco1.User" user "User.Eco1")
    (43 "Eco2.User" user "User.Eco2")
    (44 "Edge.Cuts" user)
    (45 "Margin" user)
    (46 "B.CrtYd" user "B.Courtyard")
    (47 "F.CrtYd" user "F.Courtyard")
    (48 "B.Fab" user)
    (49 "F.Fab" user)
  )
	(footprint "antmicro-footprints:antmicro-logo_scaled_20mm_mask"
		(layer "F.Cu")
    (at 178.6 108.3 -90)
    (descr "Antmicro Logo scaled 20mm F.Mask")
    (tags "Antmicro Logo scaled 20mm F.Mask")
    (property "Author" "Antmicro")
    (property "License" "Apache-2.0")
    (property "MPN" "")
    (property "Manufacturer" "")
    (property "Public" "False")
    (property "Sheetfile" "antmicro-hdmi-mipi-bridge-hw.kicad_sch")
    (property "Sheetname" "")
    (property "exclude_from_bom" "")
    (property "ki_description" "Mechanical part")
    (attr through_hole exclude_from_pos_files exclude_from_bom)
    (fp_text reference "N1" (at 0.05 -5.5 90) (layer "F.SilkS") hide
        (effects (font (size 0.7 0.7) (thickness 0.15)) (justify right bottom))
    )
    (fp_text value "antmicro_logo" (at -0.101 5.099 90) (layer "F.SilkS") hide
        (effects (font (size 0.7 0.7) (thickness 0.15)) (justify right bottom))
    )
  )
	(footprint "antmicro-footprints:C_0603_1608Metric" (layer "F.Cu")
    (at 171.65 119 180)
    (descr "Capacitor SMD 0603")
    (tags "capacitor 0603")
    (property "Author" "Antmicro")
    (property "Dielectric" "template_dielectric")
    (property "License" "Apache-2.0")
    (property "MPN" "GRM188R61A106KE69D")
    (property "Manufacturer" "Murata")
    (property "Public" "False")
    (property "Sheetfile" "channel2.kicad_sch")
    (property "Sheetname" "Channel 2")
    (property "Val" "10u")
    (property "Voltage" "")
    (property "ki_description" "SMD Multilayer Ceramic Capacitor, 10 µF, 10 V, 0603 [1608 Metric], ± 10%, X5R, GRM Series")
    (property "ki_keywords" "0603, SMT, CAPACITOR, PASSIVE, CERAMIC, MLCC")
    (attr smd)
    (fp_text reference "C40" (at -0.95 -1.5) (layer "F.SilkS")
        (effects (font (size 0.65 0.65) (thickness 0.13)) (justify right bottom))
    )
    (fp_text value "C_10u_0603" (at 0 1.6) (layer "F.Fab")
        (effects (font (size 0.65 0.65) (thickness 0.13)) (justify right bottom))
    )
    (fp_text user "${REFERENCE}" (at -1.682 3.895) (layer "F.Fab") hide
        (effects (font (size 0.7 0.7) (thickness 0.15)) (justify right bottom))
    )
    (fp_text user "Author: Antmicro" (at -1.682 4.894) (layer "F.Fab") hide
        (effects (font (size 0.7 0.7) (thickness 0.15)) (justify right bottom))
    )
    (fp_text user "License: Apache-2.0" (at -1.682 5.895) (layer "F.Fab") hide
        (effects (font (size 0.7 0.7) (thickness 0.15)) (justify right bottom))
    )
    (fp_line (start -0.15 -0.4) (end 0.15 -0.4)
      (stroke (width 0.15) (type solid)) (layer "F.SilkS"))
    (fp_line (start -0.15 0.4) (end 0.15 0.4)
      (stroke (width 0.15) (type solid)) (layer "F.SilkS"))
    (fp_rect (start -1.25 -0.65) (end 1.25 0.65)
      (stroke (width 0.05) (type solid)) (fill none) (layer "F.CrtYd"))
    (fp_rect (start -0.8 -0.4) (end 0.8 0.4)
      (stroke (width 0.15) (type solid)) (fill none) (layer "F.Fab"))
    (pad "1" smd roundrect (at -0.7 0 180) (size 0.8 1) (layers "F.Cu" "F.Paste" "F.Mask") (roundrect_rratio 0.2)
      (net 2 "GND") (pintype "passive"))
    (pad "2" smd roundrect (at 0.7 0 180) (size 0.8 1) (layers "F.Cu" "F.Paste" "F.Mask") (roundrect_rratio 0.2)
      (net 9 "+3V3") (pintype "passive"))
  )
	(footprint "antmicro-footprints:HDMI-A_Receptacle_Molex_471511001" (layer "F.Cu")
    (at 136.999 94.303 180)
    (property "Author" "Antmicro")
    (property "License" "Apache-2.0")
    (property "MPN" "471511001")
    (property "Manufacturer" "Molex")
    (property "Sheetfile" "channel1.kicad_sch")
    (property "Sheetname" "Channel 1")
    (property "ki_description" "HDMI Receptacle Connector 19 Position Surface Mount, Right Angle; Through Hole")
    (property "ki_keywords" "HDMI, CONNECTOR, SMT, HORIZONTAL")
    (attr smd)
    (fp_text reference "J2" (at 10.289 1.563 unlocked) (layer "F.SilkS")
        (effects (font (size 0.7 0.7) (thickness 0.15)) (justify left bottom))
    )
    (fp_text value "HDMI-A_Molex_471511001" (at 0 7.55 180 unlocked) (layer "F.Fab")
        (effects (font (size 0.7 0.7) (thickness 0.15)) (justify left bottom))
    )
    (fp_text user "${REFERENCE}" (at -10.001 12.48 180 unlocked) (layer "F.Fab") hide
        (effects (font (size 0.7 0.7) (thickness 0.15)) (justify left bottom))
    )
    (fp_text user "Author: Antmicro" (at -10.001 13.678 180) (layer "F.Fab") hide
        (effects (font (size 0.7 0.7) (thickness 0.15)) (justify left bottom))
    )
    (fp_text user "License: Apache-2.0" (at -10.001 14.878 180) (layer "F.Fab") hide
        (effects (font (size 0.7 0.7) (thickness 0.15)) (justify left bottom))
    )
    (fp_circle (center 4.948 -5.705) (end 4.998 -5.705)
      (stroke (width 0.15) (type solid)) (fill solid) (layer "F.SilkS"))
    (fp_rect (start -8.0296 -6.5548) (end 8.0296 6.5532)
      (stroke (width 0.05) (type solid)) (fill none) (layer "F.CrtYd"))
    (pad "1" smd rect (at 4.499 -5.056 180) (size 0.3 2.6) (layers "F.Cu" "F.Paste" "F.Mask")
      (net 74 "/Channel 1/HDMI1_D2_P") (pinfunction "D2+") (pintype "bidirectional"))
    (pad "2" smd rect (at 3.999 -5.056 180) (size 0.3 2.6) (layers "F.Cu" "F.Paste" "F.Mask")
      (net 2 "GND") (pinfunction "D2S") (pintype "passive"))
    (pad "3" smd rect (at 3.499 -5.056 180) (size 0.3 2.6) (layers "F.Cu" "F.Paste" "F.Mask")
      (net 75 "/Channel 1/HDMI1_D2_N") (pinfunction "D2-") (pintype "bidirectional"))
    (pad "4" smd rect (at 2.999 -5.056 180) (size 0.3 2.6) (layers "F.Cu" "F.Paste" "F.Mask")
      (net 76 "/Channel 1/HDMI1_D1_P") (pinfunction "D1+") (pintype "bidirectional"))
    (pad "5" smd rect (at 2.499 -5.056 180) (size 0.3 2.6) (layers "F.Cu" "F.Paste" "F.Mask")
      (net 2 "GND") (pinfunction "D1S") (pintype "passive"))
    (pad "6" smd rect (at 1.999 -5.056 180) (size 0.3 2.6) (layers "F.Cu" "F.Paste" "F.Mask")
      (net 77 "/Channel 1/HDMI1_D1_N") (pinfunction "D1-") (pintype "bidirectional"))
    (pad "7" smd rect (at 1.499 -5.056 180) (size 0.3 2.6) (layers "F.Cu" "F.Paste" "F.Mask")
      (net 78 "/Channel 1/HDMI1_D0_P") (pinfunction "D0+") (pintype "bidirectional"))
    (pad "8" smd rect (at 0.998 -5.056 180) (size 0.3 2.6) (layers "F.Cu" "F.Paste" "F.Mask")
      (net 2 "GND") (pinfunction "D0S") (pintype "passive"))
    (pad "9" smd rect (at 0.498 -5.056 180) (size 0.3 2.6) (layers "F.Cu" "F.Paste" "F.Mask")
      (net 79 "/Channel 1/HDMI1_D0_N") (pinfunction "D0-") (pintype "bidirectional"))
    (pad "10" smd rect (at 0 -5.056 180) (size 0.3 2.6) (layers "F.Cu" "F.Paste" "F.Mask")
      (net 80 "/Channel 1/HDMI1_CLK_P") (pinfunction "CK+") (pintype "bidirectional"))
    (pad "11" smd rect (at -0.5 -5.056 180) (size 0.3 2.6) (layers "F.Cu" "F.Paste" "F.Mask")
      (net 2 "GND") (pinfunction "CKS") (pintype "passive"))
    (pad "12" smd rect (at -1.002 -5.056 180) (size 0.3 2.6) (layers "F.Cu" "F.Paste" "F.Mask")
      (net 81 "/Channel 1/HDMI1_CLK_N") (pinfunction "CK-") (pintype "bidirectional"))
    (pad "13" smd rect (at -1.5 -5.056 180) (size 0.3 2.6) (layers "F.Cu" "F.Paste" "F.Mask")
      (net 82 "/Channel 1/HDMI1_CEC") (pinfunction "CEC") (pintype "bidirectional"))
    (pad "14" smd rect (at -2.001 -5.056 180) (size 0.3 2.6) (layers "F.Cu" "F.Paste" "F.Mask")
      (net 83 "/Channel 1/DUMMY1") (pinfunction "UTILITY/HEAC+") (pintype "bidirectional"))
    (pad "15" smd rect (at -2.501 -5.056 180) (size 0.3 2.6) (layers "F.Cu" "F.Paste" "F.Mask")
      (net 84 "/Channel 1/HDMI1_DDC_SCL") (pinfunction "SCL") (pintype "bidirectional"))
    (pad "16" smd rect (at -3 -5.056 180) (size 0.3 2.6) (layers "F.Cu" "F.Paste" "F.Mask")
      (net 85 "/Channel 1/HDMI1_DDC_SDA") (pinfunction "SDA") (pintype "bidirectional"))
    (pad "17" smd rect (at -3.501 -5.056 180) (size 0.3 2.6) (layers "F.Cu" "F.Paste" "F.Mask")
      (net 2 "GND") (pinfunction "GND") (pintype "power_in"))
    (pad "18" smd rect (at -4 -5.056 180) (size 0.3 2.6) (layers "F.Cu" "F.Paste" "F.Mask")
      (net 86 "/Channel 1/HDMI1_POWER") (pinfunction "+5V") (pintype "power_in"))
    (pad "19" smd rect (at -4.502 -5.056 180) (size 0.3 2.6) (layers "F.Cu" "F.Paste" "F.Mask")
      (net 87 "/Channel 1/HDMI1_HPD") (pinfunction "HPD/HEAC-") (pintype "bidirectional"))
    (pad "SH" thru_hole oval (at -7.25 -4.297 180) (size 1.5 3.3) (drill oval 0.9 2.7) (layers "*.Cu" "*.Mask")
      (net 28 "Net-(FB1-Pad2)") (pinfunction "SH") (pintype "passive"))
    (pad "SH" thru_hole oval (at -7.25 1.664 180) (size 1.5 2.3) (drill oval 0.9 1.7) (layers "*.Cu" "*.Mask")
      (net 28 "Net-(FB1-Pad2)") (pinfunction "SH") (pintype "passive"))
    (pad "SH" thru_hole oval (at 7.249 -4.297 180) (size 1.5 3.3) (drill oval 0.9 2.7) (layers "*.Cu" "*.Mask")
      (net 28 "Net-(FB1-Pad2)") (pinfunction "SH") (pintype "passive"))
    (pad "SH" thru_hole oval (at 7.249 1.664 180) (size 1.5 2.3) (drill oval 0.9 1.7) (layers "*.Cu" "*.Mask")
      (net 28 "Net-(FB1-Pad2)") (pinfunction "SH") (pintype "passive"))
  )
	(footprint "antmicro-footprints:FB_0603_1608Metric" (layer "F.Cu")
    (at 123.8 107.8 -90)
    (property "Author" "Antmicro")
    (property "Current" "")
    (property "License" "Apache-2.0")
    (property "MPN" "BLM18AG601SN1D")
    (property "Manufacturer" "Murata")
    (property "Public" "False")
    (property "Sheetfile" "channel1.kicad_sch")
    (property "Sheetname" "Channel 1")
    (property "Val" "600Z/0.5A")
    (property "ki_description" "Ferrite Bead, 0603 [1608 Metric], 600 ohm, 500 mA, BLM18A, 0.38 ohm, ± 25%, General use")
    (property "ki_keywords" "0603, SMT, FERRITE BEAD, PASSIVE")
    (attr smd)
    (fp_text reference "FB6" (at -0.74 0.74 90) (layer "F.SilkS")
        (effects (font (size 0.65 0.65) (thickness 0.13)) (justify right bottom))
    )
    (fp_text value "FB_600Z_0.5A_Murata-BLM18AG_0603" (at 0 1.5 90) (layer "F.Fab")
        (effects (font (size 0.65 0.65) (thickness 0.13)) (justify right bottom))
    )
    (fp_text user "${REFERENCE}" (at -1.653 4.6 90) (layer "F.Fab") hide
        (effects (font (size 0.7 0.7) (thickness 0.15)) (justify right bottom))
    )
    (fp_text user "Author: Antmicro" (at -1.653 3.162 90) (layer "F.Fab") hide
        (effects (font (size 0.7 0.7) (thickness 0.15)) (justify right bottom))
    )
    (fp_text user "License: Apache-2.0" (at -1.653 5.9 90) (layer "F.Fab") hide
        (effects (font (size 0.7 0.7) (thickness 0.15)) (justify right bottom))
    )
    (fp_line (start -0.15 -0.4) (end 0.15 -0.4)
      (stroke (width 0.15) (type solid)) (layer "F.SilkS"))
    (fp_line (start -0.15 0.4) (end 0.15 0.4)
      (stroke (width 0.15) (type solid)) (layer "F.SilkS"))
    (fp_rect (start -1.25 -0.65) (end 1.25 0.65)
      (stroke (width 0.05) (type solid)) (fill none) (layer "F.CrtYd"))
    (fp_line (start -0.803 0.406) (end -0.803 -0.408)
      (stroke (width 0.15) (type solid)) (layer "F.Fab"))
    (fp_line (start 0.8 -0.408) (end -0.803 -0.408)
      (stroke (width 0.15) (type solid)) (layer "F.Fab"))
    (fp_line (start 0.8 -0.408) (end 0.8 0.406)
      (stroke (width 0.15) (type solid)) (layer "F.Fab"))
    (fp_line (start 0.8 0.406) (end -0.803 0.406)
      (stroke (width 0.15) (type solid)) (layer "F.Fab"))
    (pad "1" smd roundrect (at -0.7 0 270) (size 0.8 1) (layers "F.Cu" "F.Paste" "F.Mask") (roundrect_rratio 0.2)
      (net 9 "+3V3") (pintype "passive"))
    (pad "2" smd roundrect (at 0.7 0 270) (size 0.8 1) (layers "F.Cu" "F.Paste" "F.Mask") (roundrect_rratio 0.2)
      (net 10 "Net-(Y1-EN)") (pintype "passive"))
  )
	(footprint "antmicro-footprints:R_0402_1005Metric" (layer "F.Cu")
    (at 155.08 111.45)
    (descr "Resistor SMD 0402")
    (tags "resistor SMD 0402")
    (property "Author" "Antmicro")
    (property "License" "Apache-2.0")
    (property "MPN" "CR0402-FX-22R0GLF")
    (property "Manufacturer" "Bourns")
    (property "Public" "False")
    (property "Sheetfile" "channel2.kicad_sch")
    (property "Sheetname" "Channel 2")
    (property "Tolerance" "1%")
    (property "Val" "22R")
    (property "ki_description" "SMD Chip Resistor, 22 ohm, ± 1%, 62.5 mW, 0402 [1005 Metric], Thick Film, General Purpose")
    (property "ki_keywords" "0402, SMT, RESISTOR, PASSIVE")
    (attr smd)
    (fp_text reference "R26" (at -1.57 7.52) (layer "F.SilkS")
        (effects (font (size 0.65 0.65) (thickness 0.13)) (justify left bottom))
    )
    (fp_text value "R_22R_0402" (at 0 1.4) (layer "F.Fab")
        (effects (font (size 0.65 0.65) (thickness 0.13)) (justify left bottom))
    )
    (fp_text user "License: Apache-2.0" (at -0.95 5.169) (layer "F.Fab") hide
        (effects (font (size 0.7 0.7) (thickness 0.15)) (justify left bottom))
    )
    (fp_text user "${REFERENCE}" (at -0.95 3.168) (layer "F.Fab") hide
        (effects (font (size 0.7 0.7) (thickness 0.15)) (justify left bottom))
    )
    (fp_text user "Author: Antmicro" (at -0.95 4.169) (layer "F.Fab") hide
        (effects (font (size 0.7 0.7) (thickness 0.15)) (justify left bottom))
    )
    (fp_rect (start -0.925 -0.47) (end 0.925 0.47)
      (stroke (width 0.05) (type default)) (fill none) (layer "F.CrtYd"))
    (fp_rect (start -0.5 -0.25) (end 0.5 0.25)
      (stroke (width 0.15) (type solid)) (fill none) (layer "F.Fab"))
    (pad "1" smd roundrect (at -0.48 0) (size 0.59 0.64) (layers "F.Cu" "F.Paste" "F.Mask") (roundrect_rratio 0.25)
      (net 31 "Net-(Y2-OUT)") (pintype "passive"))
    (pad "2" smd roundrect (at 0.48 0) (size 0.59 0.64) (layers "F.Cu" "F.Paste" "F.Mask") (roundrect_rratio 0.25)
      (net 27 "/Channel 2/CH2_REFCLK") (pintype "passive"))
  )
)
